(kicad_pcb
	(version 20260206)
	(generator "pcbnew")
	(generator_version "10.0")
	(general
		(thickness 1.6)
		(legacy_teardrops no)
	)
	(paper "A4")
	(title_block
		(title "m-2 — Lightning_M.2_BRD.brd")
		(comment 1 "Lightning (Wiwynn / Facebook NVMe JBOF) / footprints 69-76 of 157")
	)
	(layers
		(0 "F.Cu" signal "TOP")
		(4 "In1.Cu" signal "L2GND")
		(6 "In2.Cu" signal "L3")
		(8 "In3.Cu" signal "L4GND")
		(10 "In4.Cu" signal "L5GND")
		(12 "In5.Cu" signal "L6")
		(14 "In6.Cu" signal "L7GND")
		(2 "B.Cu" signal "BOTTOM")
		(9 "F.Adhes" user "F.Adhesive")
		(11 "B.Adhes" user "B.Adhesive")
		(13 "F.Paste" user "Package Geometry/Pastemask Top")
		(15 "B.Paste" user "Package Geometry/Pastemask Bottom")
		(5 "F.SilkS" user "Ref Des/Silkscreen Top")
		(7 "B.SilkS" user "Ref Des/Silkscreen Bottom")
		(1 "F.Mask" user "Board Geometry/Soldermask Top")
		(3 "B.Mask" user "Board Geometry/Soldermask Bottom")
		(17 "Dwgs.User" user "User.Drawings")
		(19 "Cmts.User" user "User.Comments")
		(21 "Eco1.User" user "User.Eco1")
		(23 "Eco2.User" user "User.Eco2")
		(25 "Edge.Cuts" user "Board Geometry/Outline")
		(27 "Margin" user)
		(31 "F.CrtYd" user "Package Geometry/Place Bound Top")
		(29 "B.CrtYd" user "Package Geometry/Place Bound Bottom")
		(35 "F.Fab" user "Ref Des/Assembly Top")
		(33 "B.Fab" user "Ref Des/Assembly Bottom")
	)
	(footprint ""
		(layer "F.Cu")
		(at 16.002 -76.629006)
		(property "Reference" "PC21"
			(at 0 0 0)
			(layer "F.SilkS")
			(hide yes)
			(effects
				(font
					(size 1.27 1.27)
				)
			)
		)
		(property "Value" "SC820P50V2KX-1GP"
			(at 1.1811 -2.7051 0)
			(unlocked yes)
			(layer "F.Fab")
			(hide yes)
			(effects
				(font
					(size 1.016 1.016)
					(thickness 0.1524)
				)
			)
		)
		(property "Device Type" "C402H22"
			(at 1.1811 -4.2291 0)
			(unlocked yes)
			(layer "F.Fab")
			(hide yes)
			(effects
				(font
					(size 1.016 1.016)
					(thickness 0.1524)
				)
			)
		)
		(duplicate_pad_numbers_are_jumpers no)
		(fp_rect
			(start -0.4318 0.9525)
			(end 0.4318 -0.9525)
			(stroke
				(width 0)
				(type default)
			)
			(fill no)
			(layer "F.CrtYd")
		)
		(fp_rect
			(start -0.4318 0.9525)
			(end 0.4318 -0.9525)
			(stroke
				(width 0)
				(type default)
			)
			(fill no)
			(layer "F.Fab")
		)
		(pad "1" smd custom
			(at 0 -0.4445)
			(size 0.1524 0.1524)
			(layers "F.Cu" "F.Mask" "F.Paste")
			(net "P1V8_PWR_SS_C")
			(options
				(clearance outline)
				(anchor circle)
			)
			(primitives
				(gr_poly
					(pts
						(arc
							(start 0.3048 -0.2032)
							(mid 0.275042 -0.275042)
							(end 0.2032 -0.3048)
						)
						(arc
							(start -0.2032 -0.3048)
							(mid -0.275042 -0.275042)
							(end -0.3048 -0.2032)
						)
						(arc
							(start -0.3048 0.2032)
							(mid -0.275042 0.275042)
							(end -0.2032 0.3048)
						)
						(arc
							(start 0.2032 0.3048)
							(mid 0.275042 0.275042)
							(end 0.3048 0.2032)
						)
					)
					(width 0)
					(fill yes)
				)
			)
		)
		(pad "2" smd custom
			(at 0 0.4445)
			(size 0.1524 0.1524)
			(layers "F.Cu" "F.Mask" "F.Paste")
			(net "GND")
			(options
				(clearance outline)
				(anchor circle)
			)
			(primitives
				(gr_poly
					(pts
						(arc
							(start 0.3048 -0.2032)
							(mid 0.275042 -0.275042)
							(end 0.2032 -0.3048)
						)
						(arc
							(start -0.2032 -0.3048)
							(mid -0.275042 -0.275042)
							(end -0.3048 -0.2032)
						)
						(arc
							(start -0.3048 0.2032)
							(mid -0.275042 0.275042)
							(end -0.2032 0.3048)
						)
						(arc
							(start 0.2032 0.3048)
							(mid 0.275042 0.275042)
							(end 0.3048 0.2032)
						)
					)
					(width 0)
					(fill yes)
				)
			)
		)
	)
	(footprint ""
		(layer "F.Cu")
		(at 18.161 -84.122006 180)
		(property "Reference" "PC28"
			(at 0 0 180)
			(layer "F.SilkS")
			(hide yes)
			(effects
				(font
					(size 1.27 1.27)
				)
			)
		)
		(property "Value" "SC1KP50V2KX-1GP"
			(at 1.1811 -2.7051 180)
			(unlocked yes)
			(layer "F.Fab")
			(hide yes)
			(effects
				(font
					(size 1.016 1.016)
					(thickness 0.1524)
				)
			)
		)
		(property "Device Type" "C402H22"
			(at 1.1811 -4.2291 180)
			(unlocked yes)
			(layer "F.Fab")
			(hide yes)
			(effects
				(font
					(size 1.016 1.016)
					(thickness 0.1524)
				)
			)
		)
		(duplicate_pad_numbers_are_jumpers no)
		(fp_rect
			(start -0.4318 0.9525)
			(end 0.4318 -0.9525)
			(stroke
				(width 0)
				(type default)
			)
			(fill no)
			(layer "F.CrtYd")
		)
		(fp_rect
			(start -0.4318 0.9525)
			(end 0.4318 -0.9525)
			(stroke
				(width 0)
				(type default)
			)
			(fill no)
			(layer "F.Fab")
		)
		(pad "1" smd custom
			(at 0 -0.4445 180)
			(size 0.1524 0.1524)
			(layers "F.Cu" "F.Mask" "F.Paste")
			(net "P1V8_PWR_GD")
			(options
				(clearance outline)
				(anchor circle)
			)
			(primitives
				(gr_poly
					(pts
						(arc
							(start 0.3048 -0.2032)
							(mid 0.275042 -0.275042)
							(end 0.2032 -0.3048)
						)
						(arc
							(start -0.2032 -0.3048)
							(mid -0.275042 -0.275042)
							(end -0.3048 -0.2032)
						)
						(arc
							(start -0.3048 0.2032)
							(mid -0.275042 0.275042)
							(end -0.2032 0.3048)
						)
						(arc
							(start 0.2032 0.3048)
							(mid 0.275042 0.275042)
							(end 0.3048 0.2032)
						)
					)
					(width 0)
					(fill yes)
				)
			)
		)
		(pad "2" smd custom
			(at 0 0.4445 180)
			(size 0.1524 0.1524)
			(layers "F.Cu" "F.Mask" "F.Paste")
			(net "GND")
			(options
				(clearance outline)
				(anchor circle)
			)
			(primitives
				(gr_poly
					(pts
						(arc
							(start 0.3048 -0.2032)
							(mid 0.275042 -0.275042)
							(end 0.2032 -0.3048)
						)
						(arc
							(start -0.2032 -0.3048)
							(mid -0.275042 -0.275042)
							(end -0.3048 -0.2032)
						)
						(arc
							(start -0.3048 0.2032)
							(mid -0.275042 0.275042)
							(end -0.2032 0.3048)
						)
						(arc
							(start 0.2032 0.3048)
							(mid 0.275042 0.275042)
							(end 0.3048 0.2032)
						)
					)
					(width 0)
					(fill yes)
				)
			)
		)
	)
	(footprint ""
		(layer "F.Cu")
		(at 41.91 -78.74 180)
		(property "Reference" "PC29"
			(at 0 0 180)
			(layer "F.SilkS")
			(hide yes)
			(effects
				(font
					(size 1.27 1.27)
				)
			)
		)
		(property "Value" "SC1U10V2KX-4-GP"
			(at 1.1811 -2.7051 180)
			(unlocked yes)
			(layer "F.Fab")
			(hide yes)
			(effects
				(font
					(size 1.016 1.016)
					(thickness 0.1524)
				)
			)
		)
		(property "Device Type" "C402H22"
			(at 1.1811 -4.2291 180)
			(unlocked yes)
			(layer "F.Fab")
			(hide yes)
			(effects
				(font
					(size 1.016 1.016)
					(thickness 0.1524)
				)
			)
		)
		(duplicate_pad_numbers_are_jumpers no)
		(fp_rect
			(start -0.4318 0.9525)
			(end 0.4318 -0.9525)
			(stroke
				(width 0)
				(type default)
			)
			(fill no)
			(layer "F.CrtYd")
		)
		(fp_rect
			(start -0.4318 0.9525)
			(end 0.4318 -0.9525)
			(stroke
				(width 0)
				(type default)
			)
			(fill no)
			(layer "F.Fab")
		)
		(pad "1" smd custom
			(at 0 -0.4445 180)
			(size 0.1524 0.1524)
			(layers "F.Cu" "F.Mask" "F.Paste")
			(net "GND")
			(options
				(clearance outline)
				(anchor circle)
			)
			(primitives
				(gr_poly
					(pts
						(arc
							(start 0.3048 -0.2032)
							(mid 0.275042 -0.275042)
							(end 0.2032 -0.3048)
						)
						(arc
							(start -0.2032 -0.3048)
							(mid -0.275042 -0.275042)
							(end -0.3048 -0.2032)
						)
						(arc
							(start -0.3048 0.2032)
							(mid -0.275042 0.275042)
							(end -0.2032 0.3048)
						)
						(arc
							(start 0.2032 0.3048)
							(mid 0.275042 0.275042)
							(end 0.3048 0.2032)
						)
					)
					(width 0)
					(fill yes)
				)
			)
		)
		(pad "2" smd custom
			(at 0 0.4445 180)
			(size 0.1524 0.1524)
			(layers "F.Cu" "F.Mask" "F.Paste")
			(net "P3V3_DEV_VREG")
			(options
				(clearance outline)
				(anchor circle)
			)
			(primitives
				(gr_poly
					(pts
						(arc
							(start 0.3048 -0.2032)
							(mid 0.275042 -0.275042)
							(end 0.2032 -0.3048)
						)
						(arc
							(start -0.2032 -0.3048)
							(mid -0.275042 -0.275042)
							(end -0.3048 -0.2032)
						)
						(arc
							(start -0.3048 0.2032)
							(mid -0.275042 0.275042)
							(end -0.2032 0.3048)
						)
						(arc
							(start 0.2032 0.3048)
							(mid 0.275042 0.275042)
							(end 0.3048 0.2032)
						)
					)
					(width 0)
					(fill yes)
				)
			)
		)
	)
	(footprint ""
		(layer "F.Cu")
		(at 65.532 -40.767 180)
		(property "Reference" "TP1"
			(at 0 0 180)
			(layer "F.SilkS")
			(hide yes)
			(effects
				(font
					(size 1.27 1.27)
				)
			)
		)
		(property "Value" "TPAD28-1-GP-U"
			(at 0.0508 -1.9304 180)
			(unlocked yes)
			(layer "F.Fab")
			(hide yes)
			(effects
				(font
					(size 1.016 1.016)
					(thickness 0.1524)
				)
			)
		)
		(property "Device Type" "TPAD28-1-U"
			(at 0.0508 -3.4544 180)
			(unlocked yes)
			(layer "F.Fab")
			(hide yes)
			(effects
				(font
					(size 1.016 1.016)
					(thickness 0.1524)
				)
			)
		)
		(duplicate_pad_numbers_are_jumpers no)
		(fp_poly
			(pts
				(arc
					(start -0.3556 0)
					(mid 0.3556 0)
					(end -0.3556 0)
				)
			)
			(stroke
				(width 0)
				(type default)
			)
			(fill no)
			(layer "F.CrtYd")
		)
		(fp_poly
			(pts
				(arc
					(start -0.9525 0)
					(mid 0.9525 0)
					(end -0.9525 0)
				)
			)
			(stroke
				(width 0)
				(type default)
			)
			(fill no)
			(layer "F.Fab")
		)
		(pad "1" smd circle
			(at 0 0 180)
			(size 0.7112 0.7112)
			(layers "F.Cu" "F.Mask" "F.Paste")
			(net "Z50_TEMP_1_ALERT#")
		)
	)
	(footprint ""
		(layer "F.Cu")
		(at 47.195994 -76.073 180)
		(property "Reference" "PG3"
			(at 0 0 180)
			(layer "F.SilkS")
			(hide yes)
			(effects
				(font
					(size 1.27 1.27)
				)
			)
		)
		(property "Value" "COPPER-CLOSE-GP-U"
			(at 0.0762 -2.8702 180)
			(unlocked yes)
			(layer "F.Fab")
			(hide yes)
			(effects
				(font
					(size 1.016 1.016)
					(thickness 0.1524)
				)
			)
		)
		(property "Device Type" "CON2C-U"
			(at 0.0762 -4.3942 180)
			(unlocked yes)
			(layer "F.Fab")
			(hide yes)
			(effects
				(font
					(size 1.016 1.016)
					(thickness 0.1524)
				)
			)
		)
		(duplicate_pad_numbers_are_jumpers no)
		(fp_rect
			(start -0.9398 0.9652)
			(end 0.9398 -0.9652)
			(stroke
				(width 0)
				(type default)
			)
			(fill no)
			(layer "F.CrtYd")
		)
		(fp_rect
			(start -0.9398 0.9652)
			(end 0.9398 -0.9652)
			(stroke
				(width 0)
				(type default)
			)
			(fill no)
			(layer "F.Fab")
		)
		(pad "1" smd custom
			(at 0 -0.5334 180)
			(size 0.17145 0.17145)
			(layers "F.Cu" "F.Mask" "F.Paste")
			(net "AGND_P3V3_DEV")
			(options
				(clearance outline)
				(anchor circle)
			)
			(primitives
				(gr_poly
					(pts
						(xy -0.127 0.3429) (xy -0.127 0.1651) (xy -0.635 -0.3429) (xy 0.635 -0.3429) (xy 0.127 0.1651)
						(xy 0.127 0.3429)
					)
					(width 0)
					(fill yes)
				)
			)
		)
		(pad "2" smd custom
			(at 0 0.5334 180)
			(size 0.17145 0.17145)
			(layers "F.Cu" "F.Mask" "F.Paste")
			(net "GND")
			(options
				(clearance outline)
				(anchor circle)
			)
			(primitives
				(gr_poly
					(pts
						(xy -0.635 0.3429) (xy -0.127 -0.1651) (xy -0.127 -0.3429) (xy 0.127 -0.3429) (xy 0.127 -0.1651)
						(xy 0.635 0.3429)
					)
					(width 0)
					(fill yes)
				)
			)
		)
	)
	(footprint ""
		(layer "F.Cu")
		(at 41.402 -84.582 180)
		(property "Reference" "PC32"
			(at 0 0 180)
			(layer "F.SilkS")
			(hide yes)
			(effects
				(font
					(size 1.27 1.27)
				)
			)
		)
		(property "Value" "SC10U16V5KX-1-GP"
			(at -0.0762 -6.1214 180)
			(unlocked yes)
			(layer "F.Fab")
			(hide yes)
			(effects
				(font
					(size 1.016 1.016)
					(thickness 0.1524)
				)
			)
		)
		(property "Device Type" "C805H54"
			(at -0.0762 -8.1534 180)
			(unlocked yes)
			(layer "F.Fab")
			(hide yes)
			(effects
				(font
					(size 1.016 1.016)
					(thickness 0.1524)
				)
			)
		)
		(duplicate_pad_numbers_are_jumpers no)
		(fp_line
			(start 0.635 0)
			(end -0.635 0)
			(stroke
				(width 0.508)
				(type default)
			)
			(layer "F.SilkS")
		)
		(fp_rect
			(start -0.9652 1.778)
			(end 0.9652 -1.778)
			(stroke
				(width 0)
				(type default)
			)
			(fill no)
			(layer "F.CrtYd")
		)
		(fp_poly
			(pts
				(xy -0.9652 -1.778) (xy 0.9652 -1.778) (xy 0.9652 1.778) (xy -0.9652 1.778)
			)
			(stroke
				(width 0)
				(type default)
			)
			(fill no)
			(layer "F.Fab")
		)
		(pad "1" smd rect
			(at 0 -0.9652 180)
			(size 1.397 1.143)
			(layers "F.Cu" "F.Mask" "F.Paste")
			(net "P3V3_DEV_VIN")
		)
		(pad "2" smd rect
			(at 0 0.9652 180)
			(size 1.397 1.143)
			(layers "F.Cu" "F.Mask" "F.Paste")
			(net "GND")
		)
	)
	(footprint ""
		(layer "F.Cu")
		(at 30.226 -71.628)
		(property "Reference" "R52"
			(at 0 0 0)
			(layer "F.SilkS")
			(hide yes)
			(effects
				(font
					(size 1.27 1.27)
				)
			)
		)
		(property "Value" "33R2J-2-GP"
			(at 0.064008 -3.993896 0)
			(unlocked yes)
			(layer "F.Fab")
			(hide yes)
			(effects
				(font
					(size 1.016 1.016)
					(thickness 0.1524)
				)
			)
		)
		(property "Device Type" "R402H16"
			(at 0.064008 -5.517896 0)
			(unlocked yes)
			(layer "F.Fab")
			(hide yes)
			(effects
				(font
					(size 1.016 1.016)
					(thickness 0.1524)
				)
			)
		)
		(duplicate_pad_numbers_are_jumpers no)
		(fp_line
			(start -0.508 -0.9398)
			(end -0.508 0.9398)
			(stroke
				(width 0.1524)
				(type default)
			)
			(layer "F.SilkS")
		)
		(fp_line
			(start 0.508 -0.9398)
			(end -0.508 -0.9398)
			(stroke
				(width 0.1524)
				(type default)
			)
			(layer "F.SilkS")
		)
		(fp_rect
			(start -0.508 0.9398)
			(end 0.508 -0.9398)
			(stroke
				(width 0)
				(type default)
			)
			(fill no)
			(layer "F.CrtYd")
		)
		(fp_rect
			(start -0.508 0.9398)
			(end 0.508 -0.9398)
			(stroke
				(width 0)
				(type default)
			)
			(fill no)
			(layer "F.Fab")
		)
		(pad "1" smd custom
			(at 0 -0.4445)
			(size 0.1397 0.1397)
			(layers "F.Cu" "F.Mask" "F.Paste")
			(net "Z50_SSD_B1_SMB_DATA_LR")
			(options
				(clearance outline)
				(anchor circle)
			)
			(primitives
				(gr_poly
					(pts
						(arc
							(start -0.1778 -0.2794)
							(mid -0.249642 -0.249642)
							(end -0.2794 -0.1778)
						)
						(arc
							(start -0.2794 0.1778)
							(mid -0.249642 0.249642)
							(end -0.1778 0.2794)
						)
						(arc
							(start 0.1778 0.2794)
							(mid 0.249642 0.249642)
							(end 0.2794 0.1778)
						)
						(arc
							(start 0.2794 -0.1778)
							(mid 0.249642 -0.249642)
							(end 0.1778 -0.2794)
						)
					)
					(width 0)
					(fill yes)
				)
			)
		)
		(pad "2" smd custom
			(at 0 0.4445)
			(size 0.1397 0.1397)
			(layers "F.Cu" "F.Mask" "F.Paste")
			(net "Z50_SSD_B1_SMB_DATA")
			(options
				(clearance outline)
				(anchor circle)
			)
			(primitives
				(gr_poly
					(pts
						(arc
							(start -0.1778 -0.2794)
							(mid -0.249642 -0.249642)
							(end -0.2794 -0.1778)
						)
						(arc
							(start -0.2794 0.1778)
							(mid -0.249642 0.249642)
							(end -0.1778 0.2794)
						)
						(arc
							(start 0.1778 0.2794)
							(mid 0.249642 0.249642)
							(end 0.2794 0.1778)
						)
						(arc
							(start 0.2794 -0.1778)
							(mid 0.249642 -0.249642)
							(end 0.1778 -0.2794)
						)
					)
					(width 0)
					(fill yes)
				)
			)
		)
	)
	(footprint ""
		(layer "F.Cu")
		(at 30.099 -74.93 -90)
		(property "Reference" "U6"
			(at 0 0 270)
			(layer "F.SilkS")
			(hide yes)
			(effects
				(font
					(size 1.27 1.27)
				)
			)
		)
		(property "Value" "TXS0102DCUR-1-GP"
			(at 0 -11.1252 270)
			(unlocked yes)
			(layer "F.Fab")
			(hide yes)
			(effects
				(font
					(size 1.016 1.016)
					(thickness 0.1524)
				)
			)
		)
		(property "Device Type" "SSOIC8-4H36"
			(at 0 -12.6492 270)
			(unlocked yes)
			(layer "F.Fab")
			(hide yes)
			(effects
				(font
					(size 1.016 1.016)
					(thickness 0.1524)
				)
			)
		)
		(duplicate_pad_numbers_are_jumpers no)
		(fp_line
			(start -1.2573 2.1844)
			(end -1.2573 -2.1844)
			(stroke
				(width 0.1524)
				(type default)
			)
			(layer "F.SilkS")
		)
		(fp_line
			(start 1.2573 2.1844)
			(end -1.2573 2.1844)
			(stroke
				(width 0.1524)
				(type default)
			)
			(layer "F.SilkS")
		)
		(fp_line
			(start -1.2954 0.4572)
			(end -1.2954 2.159)
			(stroke
				(width 0.4064)
				(type default)
			)
			(layer "F.SilkS")
		)
		(fp_line
			(start -1.2065 0.2667)
			(end -1.27 0.2667)
			(stroke
				(width 0.1524)
				(type default)
			)
			(layer "F.SilkS")
		)
		(fp_line
			(start -0.9017 -0.0381)
			(end -1.2065 0.2667)
			(stroke
				(width 0.1524)
				(type default)
			)
			(layer "F.SilkS")
		)
		(fp_line
			(start -1.2573 -0.3556)
			(end -1.2192 -0.3556)
			(stroke
				(width 0.1524)
				(type default)
			)
			(layer "F.SilkS")
		)
		(fp_line
			(start -1.2192 -0.3556)
			(end -0.9017 -0.0381)
			(stroke
				(width 0.1524)
				(type default)
			)
			(layer "F.SilkS")
		)
		(fp_line
			(start -1.2573 -2.1844)
			(end 1.2573 -2.1844)
			(stroke
				(width 0.1524)
				(type default)
			)
			(layer "F.SilkS")
		)
		(fp_line
			(start 1.2573 -2.1844)
			(end 1.2573 2.1844)
			(stroke
				(width 0.1524)
				(type default)
			)
			(layer "F.SilkS")
		)
		(fp_poly
			(pts
				(xy -1.5113 2.4384) (xy 1.5113 2.4384) (xy 1.5113 -2.4384) (xy -1.5113 -2.4384)
			)
			(stroke
				(width 0)
				(type default)
			)
			(fill no)
			(layer "F.CrtYd")
		)
		(fp_poly
			(pts
				(xy -1.5113 -2.4384) (xy 1.5113 -2.4384) (xy 1.5113 2.4384) (xy -1.5113 2.4384)
			)
			(stroke
				(width 0)
				(type default)
			)
			(fill no)
			(layer "F.Fab")
		)
		(pad "1" smd rect
			(at -0.75057 1.1684 270)
			(size 0.3048 1.524)
			(layers "F.Cu" "F.Mask" "F.Paste")
			(net "Z50_SSD_B1_SMB_CLK_LL")
		)
		(pad "2" smd rect
			(at -0.25019 1.1684 270)
			(size 0.3048 1.524)
			(layers "F.Cu" "F.Mask" "F.Paste")
			(net "GND")
		)
		(pad "3" smd rect
			(at 0.25019 1.1684 270)
			(size 0.3048 1.524)
			(layers "F.Cu" "F.Mask" "F.Paste")
			(net "P1V8_PWR")
		)
		(pad "4" smd rect
			(at 0.75057 1.1684 270)
			(size 0.3048 1.524)
			(layers "F.Cu" "F.Mask" "F.Paste")
			(net "Z50_SSD_B1_SMB_CLK_LR")
		)
		(pad "5" smd rect
			(at 0.75057 -1.1684 270)
			(size 0.3048 1.524)
			(layers "F.Cu" "F.Mask" "F.Paste")
			(net "Z50_SSD_B1_SMB_DATA_LR")
		)
		(pad "6" smd rect
			(at 0.25019 -1.1684 270)
			(size 0.3048 1.524)
			(layers "F.Cu" "F.Mask" "F.Paste")
			(net "SSD_B1_SMB_OE")
		)
		(pad "7" smd rect
			(at -0.25019 -1.1684 270)
			(size 0.3048 1.524)
			(layers "F.Cu" "F.Mask" "F.Paste")
			(net "P3V3_DPB")
		)
		(pad "8" smd rect
			(at -0.75057 -1.1684 270)
			(size 0.3048 1.524)
			(layers "F.Cu" "F.Mask" "F.Paste")
			(net "Z50_SSD_B1_SMB_DATA_LL")
		)
	)
)
